(kicad_pcb
	(version 20241229)
	(generator "pcbnew")
	(generator_version "9.0")
	(general
		(thickness 1.62)
		(legacy_teardrops no)
	)
	(paper "A3")
	(title_block
		(title "COM Express 7 Baseboard")
		(date "2025-02-04")
		(rev "1.1.2")
		(company "Antmicro Ltd")
		(comment 1 "www.antmicro.com")
		(comment 9 "footprints 10-15 of 802")
	)
	(layers
		(0 "F.Cu" signal)
		(4 "In1.Cu" signal)
		(6 "In2.Cu" signal)
		(8 "In3.Cu" signal)
		(10 "In4.Cu" signal)
		(12 "In5.Cu" signal)
		(14 "In6.Cu" signal)
		(2 "B.Cu" signal)
		(9 "F.Adhes" user "F.Adhesive")
		(11 "B.Adhes" user "B.Adhesive")
		(13 "F.Paste" user)
		(15 "B.Paste" user)
		(5 "F.SilkS" user "F.Silkscreen")
		(7 "B.SilkS" user "B.Silkscreen")
		(1 "F.Mask" user)
		(3 "B.Mask" user)
		(17 "Dwgs.User" user "User.Drawings")
		(19 "Cmts.User" user "User.Comments")
		(21 "Eco1.User" user "User.Eco1")
		(23 "Eco2.User" user "User.Eco2")
		(25 "Edge.Cuts" user)
		(27 "Margin" user)
		(31 "F.CrtYd" user "F.Courtyard")
		(29 "B.CrtYd" user "B.Courtyard")
		(35 "F.Fab" user)
		(33 "B.Fab" user)
	)
	(footprint "antmicro-footprints:R_0402_1005Metric"
		(layer "F.Cu")
		(at 122.05 88.06 180)
		(descr "Resistor SMD 0402")
		(tags "resistor SMD 0402")
		(property "Reference" "R26"
			(at -2.95 -0.45 0)
			(layer "F.SilkS")
			(effects
				(font
					(size 0.7 0.7)
					(thickness 0.15)
				)
				(justify right bottom)
			)
		)
		(property "Value" "R_0R_0402"
			(at -1.011843 1.772047 0)
			(layer "F.Fab")
			(effects
				(font
					(size 0.7 0.7)
					(thickness 0.15)
				)
				(justify right bottom)
			)
		)
		(property "Datasheet" "https://industrial.panasonic.com/cdbs/www-data/pdf/RDA0000/AOA0000C301.pdf"
			(at 0 0 180)
			(layer "F.Fab")
			(hide yes)
			(effects
				(font
					(size 1.27 1.27)
					(thickness 0.15)
				)
			)
		)
		(property "Author" "Antmicro"
			(at 244.1 176.12 0)
			(layer "F.Fab")
			(hide yes)
			(effects
				(font
					(size 1 1)
					(thickness 0.15)
				)
			)
		)
		(property "Current" "1A"
			(at 244.1 176.12 0)
			(layer "F.Fab")
			(hide yes)
			(effects
				(font
					(size 1 1)
					(thickness 0.15)
				)
			)
		)
		(property "License" "Apache-2.0"
			(at 244.1 176.12 0)
			(layer "F.Fab")
			(hide yes)
			(effects
				(font
					(size 1 1)
					(thickness 0.15)
				)
			)
		)
		(property "MPN" "ERJ2GE0R00X"
			(at 244.1 176.12 0)
			(layer "F.Fab")
			(hide yes)
			(effects
				(font
					(size 1 1)
					(thickness 0.15)
				)
			)
		)
		(property "Manufacturer" "Panasonic"
			(at 244.1 176.12 0)
			(layer "F.Fab")
			(hide yes)
			(effects
				(font
					(size 1 1)
					(thickness 0.15)
				)
			)
		)
		(property "Public" "False"
			(at 244.1 176.12 0)
			(layer "F.Fab")
			(hide yes)
			(effects
				(font
					(size 1 1)
					(thickness 0.15)
				)
			)
		)
		(property "Tolerance" ""
			(at 244.1 176.12 0)
			(layer "F.Fab")
			(hide yes)
			(effects
				(font
					(size 1 1)
					(thickness 0.15)
				)
			)
		)
		(property "Val" "0R"
			(at 244.1 176.12 0)
			(layer "F.Fab")
			(hide yes)
			(effects
				(font
					(size 1 1)
					(thickness 0.15)
				)
			)
		)
		(sheetname "2xUSB3.0+RJ45")
		(sheetfile "usb3+rj45.kicad_sch")
		(attr smd)
		(fp_rect
			(start -0.925 -0.47)
			(end 0.925 0.47)
			(stroke
				(width 0.05)
				(type default)
			)
			(fill no)
			(layer "F.CrtYd")
		)
		(fp_rect
			(start -0.5 -0.25)
			(end 0.5 0.25)
			(stroke
				(width 0.15)
				(type solid)
			)
			(fill no)
			(layer "F.Fab")
		)
		(pad "1" smd roundrect
			(at -0.48 0 180)
			(size 0.59 0.64)
			(layers "F.Cu" "F.Mask" "F.Paste")
			(roundrect_rratio 0.25)
			(net 314 "/2xUSB3.0+RJ45/FLG_1")
			(pintype "passive")
			(teardrops
				(best_length_ratio 0.2)
				(max_length 1)
				(best_width_ratio 0.9)
				(max_width 2)
				(curved_edges yes)
				(filter_ratio 0.9)
				(enabled yes)
				(allow_two_segments yes)
				(prefer_zone_connections yes)
			)
		)
		(pad "2" smd roundrect
			(at 0.48 0 180)
			(size 0.59 0.64)
			(layers "F.Cu" "F.Mask" "F.Paste")
			(roundrect_rratio 0.25)
			(net 553 "/2xUSB3.0+RJ45/FLG_1B")
			(pintype "passive")
			(teardrops
				(best_length_ratio 0.2)
				(max_length 1)
				(best_width_ratio 0.9)
				(max_width 2)
				(curved_edges yes)
				(filter_ratio 0.9)
				(enabled yes)
				(allow_two_segments yes)
				(prefer_zone_connections yes)
			)
		)
	)
	(footprint "antmicro-footprints:C_0402_1005Metric"
		(layer "F.Cu")
		(at 297.2 98.670999)
		(descr "Capacitor SMD 0402")
		(tags "capacitor SMD 0402")
		(property "Reference" "C66"
			(at -1.15 -0.460999 0)
			(layer "F.SilkS")
			(effects
				(font
					(size 0.7 0.7)
					(thickness 0.15)
				)
				(justify left bottom)
			)
		)
		(property "Value" "C_1u_0402"
			(at -1.022927 2.155213 0)
			(layer "F.Fab")
			(effects
				(font
					(size 0.7 0.7)
					(thickness 0.15)
				)
				(justify left bottom)
			)
		)
		(property "Datasheet" "https://product.tdk.com/en/search/capacitor/ceramic/mlcc/info?part_no=C1005X6S1A105K050BC"
			(at 0 0 0)
			(layer "F.Fab")
			(hide yes)
			(effects
				(font
					(size 1.27 1.27)
					(thickness 0.15)
				)
			)
		)
		(property "Author" "Antmicro"
			(at 0 0 0)
			(layer "F.Fab")
			(hide yes)
			(effects
				(font
					(size 1 1)
					(thickness 0.15)
				)
			)
		)
		(property "Dielectric" ""
			(at 0 0 0)
			(layer "F.Fab")
			(hide yes)
			(effects
				(font
					(size 1 1)
					(thickness 0.15)
				)
			)
		)
		(property "License" "Apache-2.0"
			(at 0 0 0)
			(layer "F.Fab")
			(hide yes)
			(effects
				(font
					(size 1 1)
					(thickness 0.15)
				)
			)
		)
		(property "MPN" "C1005X6S1A105K050BC"
			(at 0 0 0)
			(layer "F.Fab")
			(hide yes)
			(effects
				(font
					(size 1 1)
					(thickness 0.15)
				)
			)
		)
		(property "Manufacturer" "TDK"
			(at 0 0 0)
			(layer "F.Fab")
			(hide yes)
			(effects
				(font
					(size 1 1)
					(thickness 0.15)
				)
			)
		)
		(property "Public" "False"
			(at 0 0 0)
			(layer "F.Fab")
			(hide yes)
			(effects
				(font
					(size 1 1)
					(thickness 0.15)
				)
			)
		)
		(property "Val" "1u"
			(at 0 0 0)
			(layer "F.Fab")
			(hide yes)
			(effects
				(font
					(size 1 1)
					(thickness 0.15)
				)
			)
		)
		(property "Voltage" ""
			(at 0 0 0)
			(layer "F.Fab")
			(hide yes)
			(effects
				(font
					(size 1 1)
					(thickness 0.15)
				)
			)
		)
		(sheetname "Power")
		(sheetfile "power.kicad_sch")
		(attr smd)
		(fp_rect
			(start -0.925 -0.47)
			(end 0.925 0.47)
			(stroke
				(width 0.05)
				(type default)
			)
			(fill no)
			(layer "F.CrtYd")
		)
		(fp_line
			(start -0.494 -0.25)
			(end 0.504 -0.25)
			(stroke
				(width 0.15)
				(type solid)
			)
			(layer "F.Fab")
		)
		(fp_line
			(start -0.494 0.248)
			(end -0.494 -0.25)
			(stroke
				(width 0.15)
				(type solid)
			)
			(layer "F.Fab")
		)
		(fp_line
			(start 0.504 -0.25)
			(end 0.504 0.248)
			(stroke
				(width 0.15)
				(type solid)
			)
			(layer "F.Fab")
		)
		(fp_line
			(start 0.504 0.248)
			(end -0.494 0.248)
			(stroke
				(width 0.15)
				(type solid)
			)
			(layer "F.Fab")
		)
		(pad "1" smd roundrect
			(at -0.48 0)
			(size 0.59 0.64)
			(layers "F.Cu" "F.Mask" "F.Paste")
			(roundrect_rratio 0.25)
			(net 1 "GND")
			(pintype "passive")
			(teardrops
				(best_length_ratio 0.2)
				(max_length 1)
				(best_width_ratio 0.9)
				(max_width 2)
				(curved_edges yes)
				(filter_ratio 0.9)
				(enabled yes)
				(allow_two_segments yes)
				(prefer_zone_connections yes)
			)
		)
		(pad "2" smd roundrect
			(at 0.48 0)
			(size 0.59 0.64)
			(layers "F.Cu" "F.Mask" "F.Paste")
			(roundrect_rratio 0.25)
			(net 77 "+5V_AON")
			(pintype "passive")
			(teardrops
				(best_length_ratio 0.2)
				(max_length 1)
				(best_width_ratio 0.9)
				(max_width 2)
				(curved_edges yes)
				(filter_ratio 0.9)
				(enabled yes)
				(allow_two_segments yes)
				(prefer_zone_connections yes)
			)
		)
	)
	(footprint "antmicro-footprints:TP_SMD_0.75mm"
		(layer "F.Cu")
		(at 147.9 128.71)
		(property "Reference" "TP65"
			(at 0.4 -3.3 90)
			(layer "F.SilkS")
			(effects
				(font
					(size 0.7 0.7)
					(thickness 0.15)
				)
				(justify left bottom)
			)
		)
		(property "Value" "TP_0.75mm_SMD"
			(at 0 1.2 0)
			(layer "F.Fab")
			(effects
				(font
					(size 0.7 0.7)
					(thickness 0.15)
				)
				(justify left bottom)
			)
		)
		(property "Author" "Antmicro"
			(at 0 0 0)
			(layer "F.Fab")
			(hide yes)
			(effects
				(font
					(size 1 1)
					(thickness 0.15)
				)
			)
		)
		(property "License" "Apache-2.0"
			(at 0 0 0)
			(layer "F.Fab")
			(hide yes)
			(effects
				(font
					(size 1 1)
					(thickness 0.15)
				)
			)
		)
		(property "MPN" ""
			(at 0 0 0)
			(layer "F.Fab")
			(hide yes)
			(effects
				(font
					(size 1 1)
					(thickness 0.15)
				)
			)
		)
		(property "Manufacturer" ""
			(at 0 0 0)
			(layer "F.Fab")
			(hide yes)
			(effects
				(font
					(size 1 1)
					(thickness 0.15)
				)
			)
		)
		(property "Public" "False"
			(at 0 0 0)
			(layer "F.Fab")
			(hide yes)
			(effects
				(font
					(size 1 1)
					(thickness 0.15)
				)
			)
		)
		(sheetname "KR to SFI #1")
		(sheetfile "kr_sfi.kicad_sch")
		(attr exclude_from_pos_files exclude_from_bom)
		(fp_circle
			(center 0 0)
			(end 0.475 0)
			(stroke
				(width 0.05)
				(type default)
			)
			(fill no)
			(layer "F.CrtYd")
		)
		(pad "1" smd circle
			(at 0 0)
			(size 0.75 0.75)
			(layers "F.Cu" "F.Mask")
			(net 728 "Net-(U43C-AMUXA)")
			(pinfunction "1")
			(pintype "passive")
			(teardrops
				(best_length_ratio 0.4)
				(max_length 1)
				(best_width_ratio 0.9)
				(max_width 2)
				(curved_edges yes)
				(filter_ratio 0.9)
				(enabled yes)
				(allow_two_segments yes)
				(prefer_zone_connections yes)
			)
		)
	)
	(footprint "antmicro-footprints:R_0402_1005Metric"
		(layer "F.Cu")
		(at 237.77 152.930999 180)
		(descr "Resistor SMD 0402")
		(tags "resistor SMD 0402")
		(property "Reference" "R170"
			(at -3.68 -0.429001 0)
			(layer "F.SilkS")
			(effects
				(font
					(size 0.7 0.7)
					(thickness 0.15)
				)
				(justify right bottom)
			)
		)
		(property "Value" "R_1k_0402"
			(at -1.011843 1.772047 0)
			(layer "F.Fab")
			(effects
				(font
					(size 0.7 0.7)
					(thickness 0.15)
				)
				(justify right bottom)
			)
		)
		(property "Datasheet" "https://www.bourns.com/docs/product-datasheets/cr.pdf"
			(at 0 0 180)
			(layer "F.Fab")
			(hide yes)
			(effects
				(font
					(size 1.27 1.27)
					(thickness 0.15)
				)
			)
		)
		(property "Author" "Antmicro"
			(at 475.54 305.861998 0)
			(layer "F.Fab")
			(hide yes)
			(effects
				(font
					(size 1 1)
					(thickness 0.15)
				)
			)
		)
		(property "License" "Apache-2.0"
			(at 475.54 305.861998 0)
			(layer "F.Fab")
			(hide yes)
			(effects
				(font
					(size 1 1)
					(thickness 0.15)
				)
			)
		)
		(property "MPN" "CR0402-FX-1001GLF"
			(at 475.54 305.861998 0)
			(layer "F.Fab")
			(hide yes)
			(effects
				(font
					(size 1 1)
					(thickness 0.15)
				)
			)
		)
		(property "Manufacturer" "Bourns"
			(at 475.54 305.861998 0)
			(layer "F.Fab")
			(hide yes)
			(effects
				(font
					(size 1 1)
					(thickness 0.15)
				)
			)
		)
		(property "Public" "False"
			(at 475.54 305.861998 0)
			(layer "F.Fab")
			(hide yes)
			(effects
				(font
					(size 1 1)
					(thickness 0.15)
				)
			)
		)
		(property "Tolerance" "1%"
			(at 475.54 305.861998 0)
			(layer "F.Fab")
			(hide yes)
			(effects
				(font
					(size 1 1)
					(thickness 0.15)
				)
			)
		)
		(property "Val" "1k"
			(at 475.54 305.861998 0)
			(layer "F.Fab")
			(hide yes)
			(effects
				(font
					(size 1 1)
					(thickness 0.15)
				)
			)
		)
		(sheetname "Com Express 7 MGMT")
		(sheetfile "com_express_7_mgmt.kicad_sch")
		(attr smd dnp)
		(fp_rect
			(start -0.925 -0.47)
			(end 0.925 0.47)
			(stroke
				(width 0.05)
				(type default)
			)
			(fill no)
			(layer "F.CrtYd")
		)
		(fp_rect
			(start -0.5 -0.25)
			(end 0.5 0.25)
			(stroke
				(width 0.15)
				(type solid)
			)
			(fill no)
			(layer "F.Fab")
		)
		(pad "1" smd roundrect
			(at -0.48 0 180)
			(size 0.59 0.64)
			(layers "F.Cu" "F.Mask" "F.Paste")
			(roundrect_rratio 0.25)
			(net 598 "Net-(U31-~{WC})")
			(pintype "passive")
			(teardrops
				(best_length_ratio 0.2)
				(max_length 1)
				(best_width_ratio 0.9)
				(max_width 2)
				(curved_edges yes)
				(filter_ratio 0.9)
				(enabled yes)
				(allow_two_segments yes)
				(prefer_zone_connections yes)
			)
		)
		(pad "2" smd roundrect
			(at 0.48 0 180)
			(size 0.59 0.64)
			(layers "F.Cu" "F.Mask" "F.Paste")
			(roundrect_rratio 0.25)
			(net 73 "+3V3_AON")
			(pintype "passive")
			(teardrops
				(best_length_ratio 0.2)
				(max_length 1)
				(best_width_ratio 0.9)
				(max_width 2)
				(curved_edges yes)
				(filter_ratio 0.9)
				(enabled yes)
				(allow_two_segments yes)
				(prefer_zone_connections yes)
			)
		)
	)
	(footprint "antmicro-footprints:PLCC4_3.2x2.8mm"
		(layer "F.Cu")
		(at 102.45 72.31 90)
		(property "Reference" "D18"
			(at -1.25 -2.9 90)
			(unlocked yes)
			(layer "F.SilkS")
			(effects
				(font
					(size 0.7 0.7)
					(thickness 0.15)
				)
				(justify left bottom)
			)
		)
		(property "Value" "LED_RGB_PLCC4_ASMB_MTB1_0A3A2"
			(at 0 2.7 90)
			(unlocked yes)
			(layer "F.Fab")
			(effects
				(font
					(size 0.7 0.7)
					(thickness 0.15)
				)
				(justify left bottom)
			)
		)
		(property "Datasheet" "https://docs.broadcom.com/doc/AV02-4194EN"
			(at 0 0 90)
			(layer "F.Fab")
			(hide yes)
			(effects
				(font
					(size 1.27 1.27)
					(thickness 0.15)
				)
			)
		)
		(property "Author" "Antmicro"
			(at 174.76 -30.14 0)
			(layer "F.Fab")
			(hide yes)
			(effects
				(font
					(size 1 1)
					(thickness 0.15)
				)
			)
		)
		(property "Color" "R, G, B"
			(at 174.76 -30.14 0)
			(layer "F.Fab")
			(hide yes)
			(effects
				(font
					(size 1 1)
					(thickness 0.15)
				)
			)
		)
		(property "License" "Apache-2.0"
			(at 174.76 -30.14 0)
			(layer "F.Fab")
			(hide yes)
			(effects
				(font
					(size 1 1)
					(thickness 0.15)
				)
			)
		)
		(property "MPN" "ASMB-MTB1-0A3A2"
			(at 174.76 -30.14 0)
			(layer "F.Fab")
			(hide yes)
			(effects
				(font
					(size 1 1)
					(thickness 0.15)
				)
			)
		)
		(property "Manufacturer" "Avago Technologies"
			(at 174.76 -30.14 0)
			(layer "F.Fab")
			(hide yes)
			(effects
				(font
					(size 1 1)
					(thickness 0.15)
				)
			)
		)
		(sheetname "Misc")
		(sheetfile "misc.kicad_sch")
		(attr smd)
		(fp_line
			(start -1.75 -1.491)
			(end 1.947 -1.491)
			(stroke
				(width 0.15)
				(type solid)
			)
			(layer "F.SilkS")
		)
		(fp_line
			(start -1.953 1.509)
			(end 1.947 1.509)
			(stroke
				(width 0.15)
				(type solid)
			)
			(layer "F.SilkS")
		)
		(fp_circle
			(center -2 -1.45)
			(end -1.95 -1.45)
			(stroke
				(width 0.15)
				(type solid)
			)
			(fill yes)
			(layer "F.SilkS")
		)
		(fp_rect
			(start -2.25 -1.65)
			(end 2.24 1.65)
			(stroke
				(width 0.05)
				(type solid)
			)
			(fill no)
			(layer "F.CrtYd")
		)
		(fp_line
			(start 1.597 -1.391)
			(end -1.603 -1.391)
			(stroke
				(width 0.15)
				(type solid)
			)
			(layer "F.Fab")
		)
		(fp_line
			(start -0.603 -1.391)
			(end -1.603 -0.391)
			(stroke
				(width 0.15)
				(type solid)
			)
			(layer "F.Fab")
		)
		(fp_line
			(start -1.603 -1.391)
			(end -1.603 1.409)
			(stroke
				(width 0.15)
				(type solid)
			)
			(layer "F.Fab")
		)
		(fp_line
			(start 1.597 1.409)
			(end 1.597 -1.391)
			(stroke
				(width 0.15)
				(type solid)
			)
			(layer "F.Fab")
		)
		(fp_line
			(start -1.603 1.409)
			(end 1.597 1.409)
			(stroke
				(width 0.15)
				(type solid)
			)
			(layer "F.Fab")
		)
		(fp_circle
			(center -0.003 0.009)
			(end 1.117 0.009)
			(stroke
				(width 0.15)
				(type solid)
			)
			(fill no)
			(layer "F.Fab")
		)
		(pad "1" smd rect
			(at -1.255 -0.74 90)
			(size 1.5 1.1)
			(layers "F.Cu" "F.Mask" "F.Paste")
			(net 132 "Net-(D18-C_{R})")
			(pinfunction "C_{R}")
			(pintype "passive")
			(teardrops
				(best_length_ratio 0.2)
				(max_length 1)
				(best_width_ratio 0.9)
				(max_width 2)
				(curved_edges yes)
				(filter_ratio 0.9)
				(enabled yes)
				(allow_two_segments yes)
				(prefer_zone_connections yes)
			)
		)
		(pad "2" smd rect
			(at 1.245 -0.74 90)
			(size 1.5 1.1)
			(layers "F.Cu" "F.Mask" "F.Paste")
			(net 133 "Net-(D18-C_{G})")
			(pinfunction "C_{G}")
			(pintype "passive")
			(teardrops
				(best_length_ratio 0.2)
				(max_length 1)
				(best_width_ratio 0.9)
				(max_width 2)
				(curved_edges yes)
				(filter_ratio 0.9)
				(enabled yes)
				(allow_two_segments yes)
				(prefer_zone_connections yes)
			)
		)
		(pad "3" smd rect
			(at 1.245 0.76 90)
			(size 1.5 1.1)
			(layers "F.Cu" "F.Mask" "F.Paste")
			(net 134 "unconnected-(D18-C_{B}-Pad3)")
			(pinfunction "C_{B}")
			(pintype "passive+no_connect")
			(teardrops
				(best_length_ratio 0.2)
				(max_length 1)
				(best_width_ratio 0.9)
				(max_width 2)
				(curved_edges yes)
				(filter_ratio 0.9)
				(enabled yes)
				(allow_two_segments yes)
				(prefer_zone_connections yes)
			)
		)
		(pad "4" smd rect
			(at -1.255 0.76 90)
			(size 1.5 1.1)
			(layers "F.Cu" "F.Mask" "F.Paste")
			(net 77 "+5V_AON")
			(pinfunction "A")
			(pintype "passive")
			(teardrops
				(best_length_ratio 0.2)
				(max_length 1)
				(best_width_ratio 0.9)
				(max_width 2)
				(curved_edges yes)
				(filter_ratio 0.9)
				(enabled yes)
				(allow_two_segments yes)
				(prefer_zone_connections yes)
			)
		)
	)
	(footprint "antmicro-footprints:R_0402_1005Metric"
		(layer "F.Cu")
		(at 302.24 127.79 180)
		(descr "Resistor SMD 0402")
		(tags "resistor SMD 0402")
		(property "Reference" "R105"
			(at -0.96 0.53 0)
			(layer "F.SilkS")
			(effects
				(font
					(size 0.7 0.7)
					(thickness 0.15)
				)
				(justify right bottom)
			)
		)
		(property "Value" "R_1k_0402"
			(at -1.011843 1.772047 0)
			(layer "F.Fab")
			(effects
				(font
					(size 0.7 0.7)
					(thickness 0.15)
				)
				(justify right bottom)
			)
		)
		(property "Datasheet" "https://www.bourns.com/docs/product-datasheets/cr.pdf"
			(at 0 0 180)
			(layer "F.Fab")
			(hide yes)
			(effects
				(font
					(size 1.27 1.27)
					(thickness 0.15)
				)
			)
		)
		(property "Author" "Antmicro"
			(at 604.48 255.58 0)
			(layer "F.Fab")
			(hide yes)
			(effects
				(font
					(size 1 1)
					(thickness 0.15)
				)
			)
		)
		(property "License" "Apache-2.0"
			(at 604.48 255.58 0)
			(layer "F.Fab")
			(hide yes)
			(effects
				(font
					(size 1 1)
					(thickness 0.15)
				)
			)
		)
		(property "MPN" "CR0402-FX-1001GLF"
			(at 604.48 255.58 0)
			(layer "F.Fab")
			(hide yes)
			(effects
				(font
					(size 1 1)
					(thickness 0.15)
				)
			)
		)
		(property "Manufacturer" "Bourns"
			(at 604.48 255.58 0)
			(layer "F.Fab")
			(hide yes)
			(effects
				(font
					(size 1 1)
					(thickness 0.15)
				)
			)
		)
		(property "Public" "False"
			(at 604.48 255.58 0)
			(layer "F.Fab")
			(hide yes)
			(effects
				(font
					(size 1 1)
					(thickness 0.15)
				)
			)
		)
		(property "Tolerance" "1%"
			(at 604.48 255.58 0)
			(layer "F.Fab")
			(hide yes)
			(effects
				(font
					(size 1 1)
					(thickness 0.15)
				)
			)
		)
		(property "Val" "1k"
			(at 604.48 255.58 0)
			(layer "F.Fab")
			(hide yes)
			(effects
				(font
					(size 1 1)
					(thickness 0.15)
				)
			)
		)
		(sheetname "Power")
		(sheetfile "power.kicad_sch")
		(attr smd)
		(fp_rect
			(start -0.925 -0.47)
			(end 0.925 0.47)
			(stroke
				(width 0.05)
				(type default)
			)
			(fill no)
			(layer "F.CrtYd")
		)
		(fp_rect
			(start -0.5 -0.25)
			(end 0.5 0.25)
			(stroke
				(width 0.15)
				(type solid)
			)
			(fill no)
			(layer "F.Fab")
		)
		(pad "1" smd roundrect
			(at -0.48 0 180)
			(size 0.59 0.64)
			(layers "F.Cu" "F.Mask" "F.Paste")
			(roundrect_rratio 0.25)
			(net 1 "GND")
			(pintype "passive")
			(teardrops
				(best_length_ratio 0.2)
				(max_length 1)
				(best_width_ratio 0.9)
				(max_width 2)
				(curved_edges yes)
				(filter_ratio 0.9)
				(enabled yes)
				(allow_two_segments yes)
				(prefer_zone_connections yes)
			)
		)
		(pad "2" smd roundrect
			(at 0.48 0 180)
			(size 0.59 0.64)
			(layers "F.Cu" "F.Mask" "F.Paste")
			(roundrect_rratio 0.25)
			(net 365 "/Com Express 7 MGMT/PWR_OK")
			(pintype "passive")
			(teardrops
				(best_length_ratio 0.2)
				(max_length 1)
				(best_width_ratio 0.9)
				(max_width 2)
				(curved_edges yes)
				(filter_ratio 0.9)
				(enabled yes)
				(allow_two_segments yes)
				(prefer_zone_connections yes)
			)
		)
	)
)
